# T6G (Grand Teton) — schematic netlist excerpt (pin names and nets, part order shuffled) for the footprints in the layout excerpt that follows; sources: Cadence DE-HDL packaged netlist, KiCad conversion of 04192023_DAF0TMB3IC0_F0TG_MB_C_brd_V02_OCP.brd

R1213  Q_RES  1K 1% CHIP  pkg 0201LF  page 186 : A = GND ; B = RT_ROM_MUX2_OE_N

Q9001  MOSFET_NCH_DUAL  PJT138K IC  pkg SOT363XD  page 123
  S1  = GND
  G1  = PRSNT_CABLE_SWB_B2_N
  D2  = PRSNT_CABLE_SWB_B2_ISO_N
  S2  = GND
  G2  = PRSNT_CABLE_SWB_B2
  D1  = PRSNT_CABLE_SWB_B2

PL66  Q_INDUCTOR4P_14  150NH IND  pkg L_TLM117513Q-151QL_11X7-5XA  page 199
  \1\  = SW_PVDDCR_SOC_P0_SW3
  \2\  = IND_SOC_P0_CPL0
  \3\  = IND_SOC_P0_CPL3
  \4\  = PVDDCR_SOC_P0

(kicad_pcb
	(version 20260206)
	(generator "pcbnew")
	(generator_version "10.0")
	(general
		(thickness 1.6)
		(legacy_teardrops no)
	)
	(paper "A4")
	(title_block
		(title "04192023_DAF0TMB3IC0_F0TG_MB_C_brd_V02_OCP.brd")
		(comment 1 "Grand Teton / footprints 3155-3157 of 8354")
	)
	(layers
		(0 "F.Cu" signal "TOP")
		(4 "In1.Cu" signal "GND")
		(6 "In2.Cu" signal "IN1")
		(8 "In3.Cu" signal "GND1")
		(10 "In4.Cu" signal "IN2")
		(12 "In5.Cu" signal "GND2")
		(14 "In6.Cu" signal "IN3")
		(16 "In7.Cu" signal "GND3")
		(18 "In8.Cu" signal "VCC")
		(20 "In9.Cu" signal "VCC1")
		(22 "In10.Cu" signal "GND4")
		(24 "In11.Cu" signal "IN4")
		(26 "In12.Cu" signal "GND5")
		(28 "In13.Cu" signal "IN5")
		(30 "In14.Cu" signal "GND6")
		(32 "In15.Cu" signal "IN6")
		(34 "In16.Cu" signal "GND7")
		(2 "B.Cu" signal "BOTTOM")
		(9 "F.Adhes" user "F.Adhesive")
		(11 "B.Adhes" user "B.Adhesive")
		(13 "F.Paste" user "Package Geometry/Pastemask Top")
		(15 "B.Paste" user "Package Geometry/Pastemask Bottom")
		(5 "F.SilkS" user "Ref Des/Silkscreen Top")
		(7 "B.SilkS" user "Ref Des/Silkscreen Bottom")
		(1 "F.Mask" user "Board Geometry/Soldermask Top")
		(3 "B.Mask" user "Board Geometry/Soldermask Bottom")
		(17 "Dwgs.User" user "User.Drawings")
		(19 "Cmts.User" user "User.Comments")
		(21 "Eco1.User" user "User.Eco1")
		(23 "Eco2.User" user "User.Eco2")
		(25 "Edge.Cuts" user "Board Geometry/Outline")
		(27 "Margin" user)
		(31 "F.CrtYd" user "Package Geometry/Place Bound Top")
		(29 "B.CrtYd" user "Package Geometry/Place Bound Bottom")
		(35 "F.Fab" user "Ref Des/Assembly Top")
		(33 "B.Fab" user "Ref Des/Assembly Bottom")
	)
	(footprint ""
		(layer "F.Cu")
		(at 414.792922 -173.084998 180)
		(property "Reference" "PL66"
			(at 0.04445 5.886704 90)
			(unlocked yes)
			(layer "F.SilkS")
			(effects
				(font
					(size 0.7874 0.5842)
					(thickness 0.1524)
				)
				(justify left)
			)
		)
		(property "Value" ""
			(at 0 0 180)
			(layer "F.Fab")
			(effects
				(font
					(size 1.27 1.27)
				)
			)
		)
		(duplicate_pad_numbers_are_jumpers no)
		(fp_line
			(start 3.750056 5.500116)
			(end 3.750056 -5.500116)
			(stroke
				(width 0.1524)
				(type default)
			)
			(layer "F.SilkS")
		)
		(fp_line
			(start 3.750056 -5.500116)
			(end 2.393442 -5.500116)
			(stroke
				(width 0.1524)
				(type default)
			)
			(layer "F.SilkS")
		)
		(fp_line
			(start 2.393442 5.500116)
			(end 3.750056 5.500116)
			(stroke
				(width 0.1524)
				(type default)
			)
			(layer "F.SilkS")
		)
		(fp_line
			(start -2.393442 5.500116)
			(end -3.750056 5.500116)
			(stroke
				(width 0.1524)
				(type default)
			)
			(layer "F.SilkS")
		)
		(fp_line
			(start -3.750056 5.500116)
			(end -3.750056 -5.500116)
			(stroke
				(width 0.1524)
				(type default)
			)
			(layer "F.SilkS")
		)
		(fp_line
			(start -3.750056 -5.500116)
			(end -2.393442 -5.500116)
			(stroke
				(width 0.1524)
				(type default)
			)
			(layer "F.SilkS")
		)
		(fp_poly
			(pts
				(xy -3.9116 -4.249928) (xy -4.434078 -3.988562) (xy -4.434078 -4.511294)
			)
			(stroke
				(width 0)
				(type default)
			)
			(fill yes)
			(layer "F.SilkS")
		)
		(fp_line
			(start 3.750056 5.500116)
			(end 3.750056 -5.500116)
			(stroke
				(width 0.1)
				(type default)
			)
			(layer "F.Fab")
		)
		(fp_line
			(start 3.750056 -5.500116)
			(end -3.750056 -5.500116)
			(stroke
				(width 0.1)
				(type default)
			)
			(layer "F.Fab")
		)
		(fp_line
			(start -3.750056 5.500116)
			(end 3.750056 5.500116)
			(stroke
				(width 0.1)
				(type default)
			)
			(layer "F.Fab")
		)
		(fp_line
			(start -3.750056 -5.500116)
			(end -3.750056 5.500116)
			(stroke
				(width 0.1)
				(type default)
			)
			(layer "F.Fab")
		)
		(fp_poly
			(pts
				(xy -4.9276 -4.757928) (xy -4.9276 -3.741928) (xy -3.9116 -4.249928)
			)
			(stroke
				(width 0)
				(type default)
			)
			(fill yes)
			(layer "F.Fab")
		)
		(pad "1" smd rect
			(at 0 -4.249928 90)
			(size 2.413 4.5212)
			(layers "F.Cu" "F.Mask" "F.Paste")
			(net "SW_PVDDCR_SOC_P0_SW3")
		)
		(pad "2" smd rect
			(at 0 -1.175004 90)
			(size 1.3716 4.5212)
			(layers "F.Cu" "F.Mask" "F.Paste")
			(net "IND_SOC_P0_CPL0")
		)
		(pad "3" smd rect
			(at 0 1.175004 90)
			(size 1.3716 4.5212)
			(layers "F.Cu" "F.Mask" "F.Paste")
			(net "IND_SOC_P0_CPL3")
		)
		(pad "4" smd rect
			(at 0 4.249928 90)
			(size 2.413 4.5212)
			(layers "F.Cu" "F.Mask" "F.Paste")
			(net "PVDDCR_SOC_P0")
		)
	)
	(footprint ""
		(layer "F.Cu")
		(at 113.339372 -403.724618 -90)
		(property "Reference" "R1213"
			(at 0 0 270)
			(layer "F.SilkS")
			(hide yes)
			(effects
				(font
					(size 1.27 1.27)
				)
			)
		)
		(property "Value" ""
			(at 0 0 270)
			(layer "F.Fab")
			(effects
				(font
					(size 1.27 1.27)
				)
			)
		)
		(duplicate_pad_numbers_are_jumpers no)
		(fp_line
			(start -0.32512 0.175006)
			(end -0.32512 -0.175006)
			(stroke
				(width 0.1)
				(type default)
			)
			(layer "F.Fab")
		)
		(fp_line
			(start 0.32512 0.175006)
			(end -0.32512 0.175006)
			(stroke
				(width 0.1)
				(type default)
			)
			(layer "F.Fab")
		)
		(fp_line
			(start -0.32512 -0.175006)
			(end 0.32512 -0.175006)
			(stroke
				(width 0.1)
				(type default)
			)
			(layer "F.Fab")
		)
		(fp_line
			(start 0.32512 -0.175006)
			(end 0.32512 0.175006)
			(stroke
				(width 0.1)
				(type default)
			)
			(layer "F.Fab")
		)
		(pad "1" smd rect
			(at -0.2667 0 270)
			(size 0.3048 0.381)
			(layers "F.Cu" "F.Mask" "F.Paste")
			(net "GND")
		)
		(pad "2" smd rect
			(at 0.2667 0 90)
			(size 0.3048 0.381)
			(layers "F.Cu" "F.Mask" "F.Paste")
			(net "RT_ROM_MUX2_OE_N")
		)
	)
	(footprint ""
		(layer "F.Cu")
		(at 176.154334 -417.406328)
		(property "Reference" "Q9001"
			(at -2.792222 -1.82626 0)
			(unlocked yes)
			(layer "F.SilkS")
			(effects
				(font
					(size 0.7874 0.5842)
					(thickness 0.1524)
				)
				(justify left)
			)
		)
		(property "Value" ""
			(at 0 0 0)
			(layer "F.Fab")
			(effects
				(font
					(size 1.27 1.27)
				)
			)
		)
		(duplicate_pad_numbers_are_jumpers no)
		(fp_line
			(start -1.332738 -1.100074)
			(end -0.4826 -1.100074)
			(stroke
				(width 0.1524)
				(type default)
			)
			(layer "F.SilkS")
		)
		(fp_line
			(start -1.332738 1.100074)
			(end -1.332738 -1.100074)
			(stroke
				(width 0.1524)
				(type default)
			)
			(layer "F.SilkS")
		)
		(fp_line
			(start -0.4826 -1.100074)
			(end 0 -0.541274)
			(stroke
				(width 0.1524)
				(type default)
			)
			(layer "F.SilkS")
		)
		(fp_line
			(start 0 -0.541274)
			(end 0.4826 -1.100074)
			(stroke
				(width 0.1524)
				(type default)
			)
			(layer "F.SilkS")
		)
		(fp_line
			(start 0.4826 -1.100074)
			(end 1.332738 -1.100074)
			(stroke
				(width 0.1524)
				(type default)
			)
			(layer "F.SilkS")
		)
		(fp_line
			(start 1.332738 -1.100074)
			(end 1.332738 1.100074)
			(stroke
				(width 0.1524)
				(type default)
			)
			(layer "F.SilkS")
		)
		(fp_line
			(start 1.332738 1.100074)
			(end -1.332738 1.100074)
			(stroke
				(width 0.1524)
				(type default)
			)
			(layer "F.SilkS")
		)
		(fp_poly
			(pts
				(xy -2.2352 -0.298958) (xy -2.2352 -1.001014) (xy -1.533144 -0.649986)
			)
			(stroke
				(width 0)
				(type default)
			)
			(fill yes)
			(layer "F.SilkS")
		)
		(fp_line
			(start -0.674878 -1.100074)
			(end 0.674878 -1.100074)
			(stroke
				(width 0.1)
				(type default)
			)
			(layer "F.Fab")
		)
		(fp_line
			(start -0.674878 1.100074)
			(end -0.674878 -1.100074)
			(stroke
				(width 0.1)
				(type default)
			)
			(layer "F.Fab")
		)
		(fp_line
			(start 0.674878 -1.100074)
			(end 0.674878 1.100074)
			(stroke
				(width 0.1)
				(type default)
			)
			(layer "F.Fab")
		)
		(fp_line
			(start 0.674878 1.100074)
			(end -0.674878 1.100074)
			(stroke
				(width 0.1)
				(type default)
			)
			(layer "F.Fab")
		)
		(fp_poly
			(pts
				(xy -2.2352 -0.298958) (xy -2.2352 -1.001014) (xy -1.533144 -0.649986)
			)
			(stroke
				(width 0)
				(type default)
			)
			(fill yes)
			(layer "F.Fab")
		)
		(pad "1" smd rect
			(at -0.94996 -0.649986 90)
			(size 0.4318 0.508)
			(layers "F.Cu" "F.Mask" "F.Paste")
			(net "GND")
		)
		(pad "2" smd rect
			(at -0.94996 0 90)
			(size 0.4318 0.508)
			(layers "F.Cu" "F.Mask" "F.Paste")
			(net "PRSNT_CABLE_SWB_B2_N")
		)
		(pad "3" smd rect
			(at -0.94996 0.649986 90)
			(size 0.4318 0.508)
			(layers "F.Cu" "F.Mask" "F.Paste")
			(net "PRSNT_CABLE_SWB_B2_ISO_N")
		)
		(pad "4" smd rect
			(at 0.94996 0.649986 90)
			(size 0.4318 0.508)
			(layers "F.Cu" "F.Mask" "F.Paste")
			(net "GND")
		)
		(pad "5" smd rect
			(at 0.94996 0 90)
			(size 0.4318 0.508)
			(layers "F.Cu" "F.Mask" "F.Paste")
			(net "PRSNT_CABLE_SWB_B2")
		)
		(pad "6" smd rect
			(at 0.94996 -0.649986 90)
			(size 0.4318 0.508)
			(layers "F.Cu" "F.Mask" "F.Paste")
			(net "PRSNT_CABLE_SWB_B2")
		)
	)
)
